(kicad_pcb
	(version 20260206)
	(generator "pcbnew")
	(generator_version "10.0")
	(general
		(thickness 1.6)
		(legacy_teardrops no)
	)
	(paper "A4")
	(title_block
		(title "pdpb — Lightning_PDPB_BRD.brd")
		(comment 1 "Lightning (Wiwynn / Facebook NVMe JBOF) / footprints 83-83 of 1140")
	)
	(layers
		(0 "F.Cu" signal "TOP")
		(4 "In1.Cu" signal "L2GND")
		(6 "In2.Cu" signal "L3")
		(8 "In3.Cu" signal "L4VCC")
		(10 "In4.Cu" signal "L5VCC")
		(12 "In5.Cu" signal "L6")
		(14 "In6.Cu" signal "L7GND")
		(2 "B.Cu" signal "BOTTOM")
		(9 "F.Adhes" user "F.Adhesive")
		(11 "B.Adhes" user "B.Adhesive")
		(13 "F.Paste" user "Package Geometry/Pastemask Top")
		(15 "B.Paste" user "Package Geometry/Pastemask Bottom")
		(5 "F.SilkS" user "Ref Des/Silkscreen Top")
		(7 "B.SilkS" user "Ref Des/Silkscreen Bottom")
		(1 "F.Mask" user "Board Geometry/Soldermask Top")
		(3 "B.Mask" user "Board Geometry/Soldermask Bottom")
		(17 "Dwgs.User" user "User.Drawings")
		(19 "Cmts.User" user "User.Comments")
		(21 "Eco1.User" user "User.Eco1")
		(23 "Eco2.User" user "User.Eco2")
		(25 "Edge.Cuts" user "Board Geometry/Outline")
		(27 "Margin" user)
		(31 "F.CrtYd" user "Package Geometry/Place Bound Top")
		(29 "B.CrtYd" user "Package Geometry/Place Bound Bottom")
		(35 "F.Fab" user "Ref Des/Assembly Top")
		(33 "B.Fab" user "Ref Des/Assembly Bottom")
	)
	(footprint ""
		(layer "F.Cu")
		(at 226.149916 -273.670014 90)
		(property "Reference" "J2"
			(at 0 0 90)
			(layer "F.SilkS")
			(hide yes)
			(effects
				(font
					(size 1.27 1.27)
				)
			)
		)
		(property "Value" "PCISLT68-14-GP-U1"
			(at -22.225 12.7508 90)
			(unlocked yes)
			(layer "F.Fab")
			(hide yes)
			(effects
				(font
					(size 1.016 1.016)
					(thickness 0.1524)
				)
			)
		)
		(property "Device Type" "SD-78827-0001"
			(at -22.225 11.2268 90)
			(unlocked yes)
			(layer "F.Fab")
			(hide yes)
			(effects
				(font
					(size 1.016 1.016)
					(thickness 0.1524)
				)
			)
		)
		(duplicate_pad_numbers_are_jumpers no)
		(fp_line
			(start 20.4724 -3.4036)
			(end 20.4724 0.0254)
			(stroke
				(width 0.1524)
				(type default)
			)
			(layer "F.SilkS")
		)
		(fp_line
			(start -20.4724 -3.4036)
			(end 20.4724 -3.4036)
			(stroke
				(width 0.1524)
				(type default)
			)
			(layer "F.SilkS")
		)
		(fp_line
			(start 23.749 0.0254)
			(end 23.749 4.6736)
			(stroke
				(width 0.1524)
				(type default)
			)
			(layer "F.SilkS")
		)
		(fp_line
			(start 20.4724 0.0254)
			(end 23.749 0.0254)
			(stroke
				(width 0.1524)
				(type default)
			)
			(layer "F.SilkS")
		)
		(fp_line
			(start -20.4724 0.0254)
			(end -20.4724 -3.4036)
			(stroke
				(width 0.1524)
				(type default)
			)
			(layer "F.SilkS")
		)
		(fp_line
			(start -23.749 0.0254)
			(end -20.4724 0.0254)
			(stroke
				(width 0.1524)
				(type default)
			)
			(layer "F.SilkS")
		)
		(fp_line
			(start 23.117556 1.803908)
			(end 23.117556 2.896108)
			(stroke
				(width 0.3048)
				(type default)
			)
			(layer "F.SilkS")
		)
		(fp_line
			(start -20.882356 1.803908)
			(end -20.882356 2.896108)
			(stroke
				(width 0.3048)
				(type default)
			)
			(layer "F.SilkS")
		)
		(fp_line
			(start 20.882356 2.896108)
			(end 20.882356 1.803908)
			(stroke
				(width 0.3048)
				(type default)
			)
			(layer "F.SilkS")
		)
		(fp_line
			(start -23.117556 2.896108)
			(end -23.117556 1.803908)
			(stroke
				(width 0.3048)
				(type default)
			)
			(layer "F.SilkS")
		)
		(fp_line
			(start 23.749 4.6736)
			(end 20.4724 4.6736)
			(stroke
				(width 0.1524)
				(type default)
			)
			(layer "F.SilkS")
		)
		(fp_line
			(start 20.4724 4.6736)
			(end 20.4724 12.0142)
			(stroke
				(width 0.1524)
				(type default)
			)
			(layer "F.SilkS")
		)
		(fp_line
			(start -20.4724 4.6736)
			(end -23.749 4.6736)
			(stroke
				(width 0.1524)
				(type default)
			)
			(layer "F.SilkS")
		)
		(fp_line
			(start -23.749 4.6736)
			(end -23.749 0.0254)
			(stroke
				(width 0.1524)
				(type default)
			)
			(layer "F.SilkS")
		)
		(fp_line
			(start 17.8435 10.3124)
			(end -17.8435 10.3124)
			(stroke
				(width 0.1524)
				(type default)
			)
			(layer "F.SilkS")
		)
		(fp_line
			(start -17.8435 10.3124)
			(end -17.8435 12.0142)
			(stroke
				(width 0.1524)
				(type default)
			)
			(layer "F.SilkS")
		)
		(fp_line
			(start 20.4724 12.0142)
			(end 17.8435 12.0142)
			(stroke
				(width 0.1524)
				(type default)
			)
			(layer "F.SilkS")
		)
		(fp_line
			(start 17.8435 12.0142)
			(end 17.8435 10.3124)
			(stroke
				(width 0.1524)
				(type default)
			)
			(layer "F.SilkS")
		)
		(fp_line
			(start -17.8435 12.0142)
			(end -20.4724 12.0142)
			(stroke
				(width 0.1524)
				(type default)
			)
			(layer "F.SilkS")
		)
		(fp_line
			(start -20.4724 12.0142)
			(end -20.4724 4.6736)
			(stroke
				(width 0.1524)
				(type default)
			)
			(layer "F.SilkS")
		)
		(fp_arc
			(start 20.882356 1.803908)
			(mid 21.999956 0.686308)
			(end 23.117556 1.803908)
			(stroke
				(width 0.3048)
				(type default)
			)
			(layer "F.SilkS")
		)
		(fp_arc
			(start -23.117556 1.803908)
			(mid -21.999956 0.686308)
			(end -20.882356 1.803908)
			(stroke
				(width 0.3048)
				(type default)
			)
			(layer "F.SilkS")
		)
		(fp_arc
			(start 23.117556 2.896108)
			(mid 21.999956 4.013708)
			(end 20.882356 2.896108)
			(stroke
				(width 0.3048)
				(type default)
			)
			(layer "F.SilkS")
		)
		(fp_arc
			(start -20.882356 2.896108)
			(mid -21.999956 4.013708)
			(end -23.117556 2.896108)
			(stroke
				(width 0.3048)
				(type default)
			)
			(layer "F.SilkS")
		)
		(fp_poly
			(pts
				(xy -20.2184 11.7602) (xy -20.2184 4.4196) (xy -23.495 4.4196) (xy -23.495 0.2794) (xy -20.2184 0.2794)
				(xy -20.2184 -3.1496) (xy 20.2184 -3.1496) (xy 20.2184 0.2794) (xy 23.495 0.2794) (xy 23.495 4.4196)
				(xy 20.2184 4.4196) (xy 20.2184 11.7602) (xy 18.0975 11.7602) (xy 18.0975 10.0584) (xy -18.0975 10.0584)
				(xy -18.0975 11.7602)
			)
			(stroke
				(width 0)
				(type default)
			)
			(fill no)
			(layer "F.CrtYd")
		)
		(fp_poly
			(pts
				(xy -21.2471 16.256) (xy -21.2471 4.9276) (xy -24.003 4.9276) (xy -24.003 -0.2286) (xy -20.7264 -0.2286)
				(xy -20.7264 -3.6576) (xy 20.7264 -3.6576) (xy 20.7264 -0.2286) (xy 24.003 -0.2286) (xy 24.003 -0.00635)
				(xy 20.2184 -0.00635) (xy 20.2184 -3.1496) (xy -20.2184 -3.1496) (xy -20.2184 0.2794) (xy -23.495 0.2794)
				(xy -23.495 4.4196) (xy -20.2184 4.4196) (xy -20.2184 11.7602) (xy -18.0975 11.7602) (xy -18.0975 10.0584)
				(xy 18.0975 10.0584) (xy 18.0975 11.7602) (xy 20.2184 11.7602) (xy 20.2184 4.4196) (xy 23.495 4.4196)
				(xy 23.495 0.2794) (xy 20.2184 0.2794) (xy 20.2184 0.00635) (xy 24.003 0.00635) (xy 24.003 4.9276)
				(xy 21.2471 4.9276) (xy 21.2471 16.256)
			)
			(stroke
				(width 0)
				(type default)
			)
			(fill no)
			(layer "F.CrtYd")
		)
		(fp_poly
			(pts
				(xy -21.2471 16.256) (xy -21.2471 4.9276) (xy -24.003 4.9276) (xy -24.003 -0.2286) (xy -20.7264 -0.2286)
				(xy -20.7264 -3.6576) (xy 20.7264 -3.6576) (xy 20.7264 -0.2286) (xy 24.003 -0.2286) (xy 24.003 4.9276)
				(xy 21.2471 4.9276) (xy 21.2471 16.256)
			)
			(stroke
				(width 0)
				(type default)
			)
			(fill no)
			(layer "F.Fab")
		)
		(pad "" np_thru_hole circle
			(at -18.999962 0 90)
			(size 0.254 0.254)
			(drill 1.8542)
			(layers "*.Cu" "*.Mask")
			(clearance 1.1557)
			(thermal_gap 1.1557)
		)
		(pad "" np_thru_hole circle
			(at 18.999962 0 90)
			(size 0.254 0.254)
			(drill 1.8542)
			(layers "*.Cu" "*.Mask")
			(clearance 1.1557)
			(thermal_gap 1.1557)
		)
		(pad "E1" smd rect
			(at -7.079996 1.240028 90)
			(size 0.508 2.0066)
			(layers "F.Cu" "F.Mask" "F.Paste")
			(net "PE_CLK100M_DR2_2_P")
		)
		(pad "E2" smd rect
			(at -6.279896 1.240028 90)
			(size 0.508 2.0066)
			(layers "F.Cu" "F.Mask" "F.Paste")
			(net "PE_CLK100M_DR2_2_N")
		)
		(pad "E3" smd rect
			(at -5.48005 1.240028 90)
			(size 0.508 2.0066)
			(layers "F.Cu" "F.Mask" "F.Paste")
			(net "P3V3")
		)
		(pad "E4" smd rect
			(at -4.67995 1.240028 90)
			(size 0.508 2.0066)
			(layers "F.Cu" "F.Mask" "F.Paste")
			(net "SSD2_PERST_N")
		)
		(pad "E5" smd rect
			(at -3.880104 1.240028 90)
			(size 0.508 2.0066)
			(layers "F.Cu" "F.Mask" "F.Paste")
			(net "SSD2_PERST_N")
		)
		(pad "E6" smd rect
			(at -3.080004 1.240028 90)
			(size 0.508 2.0066)
			(layers "F.Cu" "F.Mask" "F.Paste")
			(net "Net_1197")
		)
		(pad "E7" smd rect
			(at -15.48003 -1.949958 90)
			(size 0.508 2.0066)
			(layers "F.Cu" "F.Mask" "F.Paste")
			(net "PE_CLK100M_DR2_1_P")
		)
		(pad "E8" smd rect
			(at -14.67993 -1.949958 90)
			(size 0.508 2.0066)
			(layers "F.Cu" "F.Mask" "F.Paste")
			(net "PE_CLK100M_DR2_1_N")
		)
		(pad "E9" smd rect
			(at -13.880084 -1.949958 90)
			(size 0.508 2.0066)
			(layers "F.Cu" "F.Mask" "F.Paste")
			(net "GND")
		)
		(pad "E10" smd rect
			(at -13.079984 -1.949958 90)
			(size 0.508 2.0066)
			(layers "F.Cu" "F.Mask" "F.Paste")
			(net "PE_TX1_DR2_N")
		)
		(pad "E11" smd rect
			(at -12.279884 -1.949958 90)
			(size 0.508 2.0066)
			(layers "F.Cu" "F.Mask" "F.Paste")
			(net "PE_TX1_DR2_P")
		)
		(pad "E12" smd rect
			(at -11.480038 -1.949958 90)
			(size 0.508 2.0066)
			(layers "F.Cu" "F.Mask" "F.Paste")
			(net "GND")
		)
		(pad "E13" smd rect
			(at -10.679938 -1.949958 90)
			(size 0.508 2.0066)
			(layers "F.Cu" "F.Mask" "F.Paste")
			(net "PE_RX1_DR2_N")
		)
		(pad "E14" smd rect
			(at -9.880092 -1.949958 90)
			(size 0.508 2.0066)
			(layers "F.Cu" "F.Mask" "F.Paste")
			(net "PE_RX1_DR2_P")
		)
		(pad "E15" smd rect
			(at -9.079992 -1.949958 90)
			(size 0.508 2.0066)
			(layers "F.Cu" "F.Mask" "F.Paste")
			(net "GND")
		)
		(pad "E16" smd rect
			(at -8.279892 -1.949958 90)
			(size 0.508 2.0066)
			(layers "F.Cu" "F.Mask" "F.Paste")
			(net "Net_1204")
		)
		(pad "E17" smd rect
			(at 9.320022 -1.949958 90)
			(size 0.508 2.0066)
			(layers "F.Cu" "F.Mask" "F.Paste")
			(net "PE_TX4_DR2_N")
		)
		(pad "E18" smd rect
			(at 10.120122 -1.949958 90)
			(size 0.508 2.0066)
			(layers "F.Cu" "F.Mask" "F.Paste")
			(net "PE_TX4_DR2_P")
		)
		(pad "E19" smd rect
			(at 10.919968 -1.949958 90)
			(size 0.508 2.0066)
			(layers "F.Cu" "F.Mask" "F.Paste")
			(net "GND")
		)
		(pad "E20" smd rect
			(at 11.720068 -1.949958 90)
			(size 0.508 2.0066)
			(layers "F.Cu" "F.Mask" "F.Paste")
			(net "PE_RX4_DR2_N")
		)
		(pad "E21" smd rect
			(at 12.519914 -1.949958 90)
			(size 0.508 2.0066)
			(layers "F.Cu" "F.Mask" "F.Paste")
			(net "PE_RX4_DR2_P")
		)
		(pad "E22" smd rect
			(at 13.320014 -1.949958 90)
			(size 0.508 2.0066)
			(layers "F.Cu" "F.Mask" "F.Paste")
			(net "GND")
		)
		(pad "E23" smd rect
			(at 14.120114 -1.949958 90)
			(size 0.508 2.0066)
			(layers "F.Cu" "F.Mask" "F.Paste")
			(net "SCL_DR2_R")
		)
		(pad "E24" smd rect
			(at 14.91996 -1.949958 90)
			(size 0.508 2.0066)
			(layers "F.Cu" "F.Mask" "F.Paste")
			(net "SDA_DR2_R")
		)
		(pad "E25" smd rect
			(at 15.72006 -1.949958 90)
			(size 0.508 2.0066)
			(layers "F.Cu" "F.Mask" "F.Paste")
			(net "DUALPORTEN#2")
		)
		(pad "P1" smd rect
			(at -1.905 0.824992 90)
			(size 0.6604 2.0574)
			(layers "F.Cu" "F.Mask" "F.Paste")
			(net "Net_1200")
		)
		(pad "P2" smd rect
			(at -0.635 0.824992 90)
			(size 0.6604 2.0574)
			(layers "F.Cu" "F.Mask" "F.Paste")
			(net "Net_1199")
		)
		(pad "P3" smd rect
			(at 0.635 0.824992 90)
			(size 0.6604 2.0574)
			(layers "F.Cu" "F.Mask" "F.Paste")
			(net "Net_1198")
		)
		(pad "P4" smd rect
			(at 1.905 0.824992 90)
			(size 0.6604 2.0574)
			(layers "F.Cu" "F.Mask" "F.Paste")
			(net "SSD2_CLK0_OE_N")
		)
		(pad "P5" smd rect
			(at 3.175 0.824992 90)
			(size 0.6604 2.0574)
			(layers "F.Cu" "F.Mask" "F.Paste")
			(net "GND")
		)
		(pad "P6" smd rect
			(at 4.445 0.824992 90)
			(size 0.6604 2.0574)
			(layers "F.Cu" "F.Mask" "F.Paste")
			(net "GND")
		)
		(pad "P7" smd rect
			(at 5.715 0.824992 90)
			(size 0.6604 2.0574)
			(layers "F.Cu" "F.Mask" "F.Paste")
			(net "Net_93")
		)
		(pad "P8" smd rect
			(at 6.985 0.824992 90)
			(size 0.6604 2.0574)
			(layers "F.Cu" "F.Mask" "F.Paste")
			(net "Net_65")
		)
		(pad "P9" smd rect
			(at 8.255 0.824992 90)
			(size 0.6604 2.0574)
			(layers "F.Cu" "F.Mask" "F.Paste")
			(net "Net_79")
		)
		(pad "P10" smd rect
			(at 9.525 0.824992 90)
			(size 0.6604 2.0574)
			(layers "F.Cu" "F.Mask" "F.Paste")
			(net "SSD_PRSNT_NET2")
		)
		(pad "P11" smd rect
			(at 10.795 0.824992 90)
			(size 0.6604 2.0574)
			(layers "F.Cu" "F.Mask" "F.Paste")
			(net "SSD_ACT_DR2")
		)
		(pad "P12" smd rect
			(at 12.065 0.824992 90)
			(size 0.6604 2.0574)
			(layers "F.Cu" "F.Mask" "F.Paste")
			(net "GND")
		)
		(pad "P13" smd rect
			(at 13.335 0.824992 90)
			(size 0.6604 2.0574)
			(layers "F.Cu" "F.Mask" "F.Paste")
			(net "12V_PRECH_SSD2")
		)
		(pad "P14" smd rect
			(at 14.605 0.824992 90)
			(size 0.6604 2.0574)
			(layers "F.Cu" "F.Mask" "F.Paste")
			(net "P12V_SSD2")
		)
		(pad "P15" smd rect
			(at 15.875 0.824992 90)
			(size 0.6604 2.0574)
			(layers "F.Cu" "F.Mask" "F.Paste")
			(net "P12V_SSD2")
		)
		(pad "PTH1" thru_hole oval
			(at -21.999956 2.350008 90)
			(size 1.524 2.6162)
			(drill oval 0.8128 1.905)
			(layers "*.Cu" "*.Mask")
			(remove_unused_layers no)
			(net "Net_1209")
			(clearance 0.1524)
			(thermal_gap 0.1524)
		)
		(pad "PTH2" thru_hole oval
			(at 21.999956 2.350008 90)
			(size 1.524 2.6162)
			(drill oval 0.8128 1.905)
			(layers "*.Cu" "*.Mask")
			(remove_unused_layers no)
			(net "Net_1193")
			(clearance 0.1524)
			(thermal_gap 0.1524)
		)
		(pad "S1" smd rect
			(at -15.875 0.824992 90)
			(size 0.6604 2.0574)
			(layers "F.Cu" "F.Mask" "F.Paste")
			(net "GND")
		)
		(pad "S2" smd rect
			(at -14.605 0.824992 90)
			(size 0.6604 2.0574)
			(layers "F.Cu" "F.Mask" "F.Paste")
			(net "Net_1208")
		)
		(pad "S3" smd rect
			(at -13.335 0.824992 90)
			(size 0.6604 2.0574)
			(layers "F.Cu" "F.Mask" "F.Paste")
			(net "Net_1207")
		)
		(pad "S4" smd rect
			(at -12.065 0.824992 90)
			(size 0.6604 2.0574)
			(layers "F.Cu" "F.Mask" "F.Paste")
			(net "GND")
		)
		(pad "S5" smd rect
			(at -10.795 0.824992 90)
			(size 0.6604 2.0574)
			(layers "F.Cu" "F.Mask" "F.Paste")
			(net "Net_1206")
		)
		(pad "S6" smd rect
			(at -9.525 0.824992 90)
			(size 0.6604 2.0574)
			(layers "F.Cu" "F.Mask" "F.Paste")
			(net "Net_1205")
		)
		(pad "S7" smd rect
			(at -8.255 0.824992 90)
			(size 0.6604 2.0574)
			(layers "F.Cu" "F.Mask" "F.Paste")
			(net "GND")
		)
		(pad "S8" smd rect
			(at -7.480046 -1.949958 90)
			(size 0.508 2.0066)
			(layers "F.Cu" "F.Mask" "F.Paste")
			(net "GND")
		)
		(pad "S9" smd rect
			(at -6.679946 -1.949958 90)
			(size 0.508 2.0066)
			(layers "F.Cu" "F.Mask" "F.Paste")
			(net "Net_1203")
		)
		(pad "S10" smd rect
			(at -5.8801 -1.949958 90)
			(size 0.508 2.0066)
			(layers "F.Cu" "F.Mask" "F.Paste")
			(net "Net_1202")
		)
		(pad "S11" smd rect
			(at -5.08 -1.949958 90)
			(size 0.508 2.0066)
			(layers "F.Cu" "F.Mask" "F.Paste")
			(net "GND")
		)
		(pad "S12" smd rect
			(at -4.2799 -1.949958 90)
			(size 0.508 2.0066)
			(layers "F.Cu" "F.Mask" "F.Paste")
			(net "Net_1201")
		)
		(pad "S13" smd rect
			(at -3.480054 -1.949958 90)
			(size 0.508 2.0066)
			(layers "F.Cu" "F.Mask" "F.Paste")
			(net "Net_1196")
		)
		(pad "S14" smd rect
			(at -2.679954 -1.949958 90)
			(size 0.508 2.0066)
			(layers "F.Cu" "F.Mask" "F.Paste")
			(net "GND")
		)
		(pad "S15" smd rect
			(at -1.880108 -1.949958 90)
			(size 0.508 2.0066)
			(layers "F.Cu" "F.Mask" "F.Paste")
			(net "Net_1195")
		)
		(pad "S16" smd rect
			(at -1.080008 -1.949958 90)
			(size 0.508 2.0066)
			(layers "F.Cu" "F.Mask" "F.Paste")
			(net "GND")
		)
		(pad "S17" smd rect
			(at -0.279908 -1.949958 90)
			(size 0.508 2.0066)
			(layers "F.Cu" "F.Mask" "F.Paste")
			(net "PE_TX2_DR2_N")
		)
		(pad "S18" smd rect
			(at 0.519938 -1.949958 90)
			(size 0.508 2.0066)
			(layers "F.Cu" "F.Mask" "F.Paste")
			(net "PE_TX2_DR2_P")
		)
		(pad "S19" smd rect
			(at 1.320038 -1.949958 90)
			(size 0.508 2.0066)
			(layers "F.Cu" "F.Mask" "F.Paste")
			(net "GND")
		)
		(pad "S20" smd rect
			(at 2.119884 -1.949958 90)
			(size 0.508 2.0066)
			(layers "F.Cu" "F.Mask" "F.Paste")
			(net "PE_RX2_DR2_N")
		)
		(pad "S21" smd rect
			(at 2.919984 -1.949958 90)
			(size 0.508 2.0066)
			(layers "F.Cu" "F.Mask" "F.Paste")
			(net "PE_RX2_DR2_P")
		)
		(pad "S22" smd rect
			(at 3.720084 -1.949958 90)
			(size 0.508 2.0066)
			(layers "F.Cu" "F.Mask" "F.Paste")
			(net "GND")
		)
		(pad "S23" smd rect
			(at 4.51993 -1.949958 90)
			(size 0.508 2.0066)
			(layers "F.Cu" "F.Mask" "F.Paste")
			(net "PE_TX3_DR2_N")
		)
		(pad "S24" smd rect
			(at 5.32003 -1.949958 90)
			(size 0.508 2.0066)
			(layers "F.Cu" "F.Mask" "F.Paste")
			(net "PE_TX3_DR2_P")
		)
		(pad "S25" smd rect
			(at 6.119876 -1.949958 90)
			(size 0.508 2.0066)
			(layers "F.Cu" "F.Mask" "F.Paste")
			(net "GND")
		)
		(pad "S26" smd rect
			(at 6.919976 -1.949958 90)
			(size 0.508 2.0066)
			(layers "F.Cu" "F.Mask" "F.Paste")
			(net "PE_RX3_DR2_N")
		)
		(pad "S27" smd rect
			(at 7.720076 -1.949958 90)
			(size 0.508 2.0066)
			(layers "F.Cu" "F.Mask" "F.Paste")
			(net "PE_RX3_DR2_P")
		)
		(pad "S28" smd rect
			(at 8.519922 -1.949958 90)
			(size 0.508 2.0066)
			(layers "F.Cu" "F.Mask" "F.Paste")
			(net "GND")
		)
		(zone
			(layers "F.Cu" "B.Cu" "In1.Cu" "In2.Cu" "In3.Cu" "In4.Cu" "In5.Cu" "In6.Cu")
			(hatch none 0.5)
			(connect_pads
				(clearance 0)
			)
			(min_thickness 0.25)
			(keepout
				(tracks not_allowed)
				(vias allowed)
				(pads allowed)
				(copperpour not_allowed)
				(footprints allowed)
			)
			(placement
				(enabled no)
				(sheetname "")
			)
			(fill
				(thermal_gap 0.5)
				(thermal_bridge_width 0.5)
				(island_removal_mode 0)
			)
			(polygon
				(pts
					(arc
						(start 227.381816 -292.669976)
						(mid 224.918016 -292.669976)
						(end 227.381816 -292.669976)
					)
				)
			)
		)
		(zone
			(layers "F.Cu" "B.Cu" "In1.Cu" "In2.Cu" "In3.Cu" "In4.Cu" "In5.Cu" "In6.Cu")
			(hatch none 0.5)
			(connect_pads
				(clearance 0)
			)
			(min_thickness 0.25)
			(keepout
				(tracks not_allowed)
				(vias allowed)
				(pads allowed)
				(copperpour not_allowed)
				(footprints allowed)
			)
			(placement
				(enabled no)
				(sheetname "")
			)
			(fill
				(thermal_gap 0.5)
				(thermal_bridge_width 0.5)
				(island_removal_mode 0)
			)
			(polygon
				(pts
					(arc
						(start 227.381816 -254.670052)
						(mid 224.918016 -254.670052)
						(end 227.381816 -254.670052)
					)
				)
			)
		)
	)
)
